(kicad_pcb
	(version 20260206)
	(generator "pcbnew")
	(generator_version "10.0")
	(general
		(thickness 1.6)
		(legacy_teardrops no)
	)
	(paper "A4")
	(title_block
		(title "04192023_DAF0TMB3IC0_F0TG_MB_C_brd_V02_OCP.brd")
		(comment 1 "Grand Teton / footprints 4504-4511 of 8354")
	)
	(layers
		(0 "F.Cu" signal "TOP")
		(4 "In1.Cu" signal "GND")
		(6 "In2.Cu" signal "IN1")
		(8 "In3.Cu" signal "GND1")
		(10 "In4.Cu" signal "IN2")
		(12 "In5.Cu" signal "GND2")
		(14 "In6.Cu" signal "IN3")
		(16 "In7.Cu" signal "GND3")
		(18 "In8.Cu" signal "VCC")
		(20 "In9.Cu" signal "VCC1")
		(22 "In10.Cu" signal "GND4")
		(24 "In11.Cu" signal "IN4")
		(26 "In12.Cu" signal "GND5")
		(28 "In13.Cu" signal "IN5")
		(30 "In14.Cu" signal "GND6")
		(32 "In15.Cu" signal "IN6")
		(34 "In16.Cu" signal "GND7")
		(2 "B.Cu" signal "BOTTOM")
		(9 "F.Adhes" user "F.Adhesive")
		(11 "B.Adhes" user "B.Adhesive")
		(13 "F.Paste" user "Package Geometry/Pastemask Top")
		(15 "B.Paste" user "Package Geometry/Pastemask Bottom")
		(5 "F.SilkS" user "Ref Des/Silkscreen Top")
		(7 "B.SilkS" user "Ref Des/Silkscreen Bottom")
		(1 "F.Mask" user "Board Geometry/Soldermask Top")
		(3 "B.Mask" user "Board Geometry/Soldermask Bottom")
		(17 "Dwgs.User" user "User.Drawings")
		(19 "Cmts.User" user "User.Comments")
		(21 "Eco1.User" user "User.Eco1")
		(23 "Eco2.User" user "User.Eco2")
		(25 "Edge.Cuts" user "Board Geometry/Outline")
		(27 "Margin" user)
		(31 "F.CrtYd" user "Package Geometry/Place Bound Top")
		(29 "B.CrtYd" user "Package Geometry/Place Bound Bottom")
		(35 "F.Fab" user "Ref Des/Assembly Top")
		(33 "B.Fab" user "Ref Des/Assembly Bottom")
	)
	(footprint ""
		(layer "F.Cu")
		(at 242.952016 -304.162206 90)
		(property "Reference" "PL6501"
			(at -7.490206 7.391654 90)
			(unlocked yes)
			(layer "F.SilkS")
			(effects
				(font
					(size 0.7874 0.5842)
					(thickness 0.1524)
				)
				(justify left)
			)
		)
		(property "Value" ""
			(at 0 0 90)
			(layer "F.Fab")
			(effects
				(font
					(size 1.27 1.27)
				)
			)
		)
		(duplicate_pad_numbers_are_jumpers no)
		(fp_line
			(start 7.4422 -6.400038)
			(end 7.4422 6.400038)
			(stroke
				(width 0.1524)
				(type default)
			)
			(layer "F.SilkS")
		)
		(fp_line
			(start -7.4422 -6.400038)
			(end 7.4422 -6.400038)
			(stroke
				(width 0.1524)
				(type default)
			)
			(layer "F.SilkS")
		)
		(fp_line
			(start 7.4422 6.400038)
			(end -7.4422 6.400038)
			(stroke
				(width 0.1524)
				(type default)
			)
			(layer "F.SilkS")
		)
		(fp_line
			(start -7.4422 6.400038)
			(end -7.4422 -6.400038)
			(stroke
				(width 0.1524)
				(type default)
			)
			(layer "F.SilkS")
		)
		(fp_line
			(start 6.938264 -6.400038)
			(end -6.862064 -6.400038)
			(stroke
				(width 0.1)
				(type default)
			)
			(layer "F.Fab")
		)
		(fp_line
			(start -6.862064 -6.400038)
			(end -6.862064 6.400038)
			(stroke
				(width 0.1)
				(type default)
			)
			(layer "F.Fab")
		)
		(fp_line
			(start 6.938264 6.400038)
			(end 6.938264 -6.400038)
			(stroke
				(width 0.1)
				(type default)
			)
			(layer "F.Fab")
		)
		(fp_line
			(start -6.862064 6.400038)
			(end 6.938264 6.400038)
			(stroke
				(width 0.1)
				(type default)
			)
			(layer "F.Fab")
		)
		(pad "1" smd rect
			(at -5.650484 0 90)
			(size 3.302 4.29768)
			(layers "F.Cu" "F.Mask" "F.Paste")
			(net "SW_P1V8_RETIMER_CPU0_SW")
		)
		(pad "2" smd rect
			(at 5.650484 0 90)
			(size 3.302 4.29768)
			(layers "F.Cu" "F.Mask" "F.Paste")
			(net "P1V8_CPU0_RT_1D")
		)
	)
	(footprint ""
		(layer "F.Cu")
		(at 290.15944 -397.589248)
		(property "Reference" "R837"
			(at 0 0 0)
			(layer "F.SilkS")
			(hide yes)
			(effects
				(font
					(size 1.27 1.27)
				)
			)
		)
		(property "Value" ""
			(at 0 0 0)
			(layer "F.Fab")
			(effects
				(font
					(size 1.27 1.27)
				)
			)
		)
		(duplicate_pad_numbers_are_jumpers no)
		(fp_line
			(start -0.32512 -0.175006)
			(end 0.32512 -0.175006)
			(stroke
				(width 0.1)
				(type default)
			)
			(layer "F.Fab")
		)
		(fp_line
			(start -0.32512 0.175006)
			(end -0.32512 -0.175006)
			(stroke
				(width 0.1)
				(type default)
			)
			(layer "F.Fab")
		)
		(fp_line
			(start 0.32512 -0.175006)
			(end 0.32512 0.175006)
			(stroke
				(width 0.1)
				(type default)
			)
			(layer "F.Fab")
		)
		(fp_line
			(start 0.32512 0.175006)
			(end -0.32512 0.175006)
			(stroke
				(width 0.1)
				(type default)
			)
			(layer "F.Fab")
		)
		(pad "1" smd rect
			(at -0.2667 0)
			(size 0.3048 0.381)
			(layers "F.Cu" "F.Mask" "F.Paste")
			(net "P1V8_CPU0_RT_1D")
		)
		(pad "2" smd rect
			(at 0.2667 0 180)
			(size 0.3048 0.381)
			(layers "F.Cu" "F.Mask" "F.Paste")
			(net "SMB_RT_CPU0_P1_ROM_R_SCL")
		)
	)
	(footprint ""
		(layer "F.Cu")
		(at 43.012106 19.444716 -90)
		(property "Reference" "PJ38_NUT"
			(at 0 0 270)
			(layer "F.SilkS")
			(hide yes)
			(effects
				(font
					(size 1.27 1.27)
				)
			)
		)
		(property "Value" ""
			(at 0 0 270)
			(layer "F.Fab")
			(effects
				(font
					(size 1.27 1.27)
				)
			)
		)
		(duplicate_pad_numbers_are_jumpers no)
		(pad "1" smd circle
			(at 0 0 270)
			(size 0.762 0.762)
			(layers "F.Cu" "F.Mask" "F.Paste")
			(net "Net_10790")
		)
	)
	(footprint ""
		(layer "F.Cu")
		(at 312.342022 -32.572706 180)
		(property "Reference" "R3860"
			(at 0 0 180)
			(layer "F.SilkS")
			(hide yes)
			(effects
				(font
					(size 1.27 1.27)
				)
			)
		)
		(property "Value" ""
			(at 0 0 180)
			(layer "F.Fab")
			(effects
				(font
					(size 1.27 1.27)
				)
			)
		)
		(duplicate_pad_numbers_are_jumpers no)
		(fp_line
			(start 0.7874 0.4064)
			(end -0.7874 0.4064)
			(stroke
				(width 0.1524)
				(type default)
			)
			(layer "F.SilkS")
		)
		(fp_line
			(start 0.7874 -0.4064)
			(end 0.7874 0.4064)
			(stroke
				(width 0.1524)
				(type default)
			)
			(layer "F.SilkS")
		)
		(fp_line
			(start -0.7874 0.4064)
			(end -0.7874 -0.4064)
			(stroke
				(width 0.1524)
				(type default)
			)
			(layer "F.SilkS")
		)
		(fp_line
			(start -0.7874 -0.4064)
			(end 0.7874 -0.4064)
			(stroke
				(width 0.1524)
				(type default)
			)
			(layer "F.SilkS")
		)
		(fp_line
			(start 0.67945 0.3048)
			(end 0.120396 0.3048)
			(stroke
				(width 0.1)
				(type default)
			)
			(layer "F.Fab")
		)
		(fp_line
			(start 0.67945 -0.3048)
			(end 0.67945 0.3048)
			(stroke
				(width 0.1)
				(type default)
			)
			(layer "F.Fab")
		)
		(fp_line
			(start 0.12065 -0.2794)
			(end 0.12065 -0.3048)
			(stroke
				(width 0.1)
				(type default)
			)
			(layer "F.Fab")
		)
		(fp_line
			(start 0.12065 -0.3048)
			(end 0.67945 -0.3048)
			(stroke
				(width 0.1)
				(type default)
			)
			(layer "F.Fab")
		)
		(fp_line
			(start 0.120396 0.3048)
			(end 0.120396 0.2794)
			(stroke
				(width 0.1)
				(type default)
			)
			(layer "F.Fab")
		)
		(fp_line
			(start 0.120396 0.2794)
			(end -0.12065 0.2794)
			(stroke
				(width 0.1)
				(type default)
			)
			(layer "F.Fab")
		)
		(fp_line
			(start -0.12065 0.3048)
			(end -0.67945 0.3048)
			(stroke
				(width 0.1)
				(type default)
			)
			(layer "F.Fab")
		)
		(fp_line
			(start -0.12065 0.2794)
			(end -0.12065 0.3048)
			(stroke
				(width 0.1)
				(type default)
			)
			(layer "F.Fab")
		)
		(fp_line
			(start -0.12065 -0.2794)
			(end 0.12065 -0.2794)
			(stroke
				(width 0.1)
				(type default)
			)
			(layer "F.Fab")
		)
		(fp_line
			(start -0.12065 -0.305054)
			(end -0.12065 -0.2794)
			(stroke
				(width 0.1)
				(type default)
			)
			(layer "F.Fab")
		)
		(fp_line
			(start -0.67945 0.3048)
			(end -0.67945 -0.305054)
			(stroke
				(width 0.1)
				(type default)
			)
			(layer "F.Fab")
		)
		(fp_line
			(start -0.67945 -0.305054)
			(end -0.12065 -0.305054)
			(stroke
				(width 0.1)
				(type default)
			)
			(layer "F.Fab")
		)
		(pad "1" smd rect
			(at -0.40005 0)
			(size 0.4572 0.508)
			(layers "F.Cu" "F.Mask" "F.Paste")
			(net "P12V_OCP_V3_2_ISENSE_MPS_MAM")
		)
		(pad "2" smd rect
			(at 0.40005 0)
			(size 0.4572 0.508)
			(layers "F.Cu" "F.Mask" "F.Paste")
			(net "P12V_OCP_V3_2_ISENSE_MAM")
		)
	)
	(footprint ""
		(layer "F.Cu")
		(at 98.344736 -123.628404 -90)
		(property "Reference" "U38"
			(at 0.808736 2.012188 90)
			(unlocked yes)
			(layer "F.SilkS")
			(effects
				(font
					(size 0.7874 0.5842)
					(thickness 0.1524)
				)
				(justify left)
			)
		)
		(property "Value" ""
			(at 0 0 270)
			(layer "F.Fab")
			(effects
				(font
					(size 1.27 1.27)
				)
			)
		)
		(duplicate_pad_numbers_are_jumpers no)
		(fp_line
			(start -1.690624 1.074928)
			(end 1.690624 1.074928)
			(stroke
				(width 0.1524)
				(type default)
			)
			(layer "F.SilkS")
		)
		(fp_line
			(start 1.690624 1.074928)
			(end 1.690624 -1.074928)
			(stroke
				(width 0.1524)
				(type default)
			)
			(layer "F.SilkS")
		)
		(fp_line
			(start 0 -0.381)
			(end -0.439928 -1.074928)
			(stroke
				(width 0.1524)
				(type default)
			)
			(layer "F.SilkS")
		)
		(fp_line
			(start -1.690624 -1.074928)
			(end -1.690624 1.074928)
			(stroke
				(width 0.1524)
				(type default)
			)
			(layer "F.SilkS")
		)
		(fp_line
			(start -0.439928 -1.074928)
			(end -1.690624 -1.074928)
			(stroke
				(width 0.1524)
				(type default)
			)
			(layer "F.SilkS")
		)
		(fp_line
			(start 0.439928 -1.074928)
			(end 0 -0.381)
			(stroke
				(width 0.1524)
				(type default)
			)
			(layer "F.SilkS")
		)
		(fp_line
			(start 1.690624 -1.074928)
			(end 0.439928 -1.074928)
			(stroke
				(width 0.1524)
				(type default)
			)
			(layer "F.SilkS")
		)
		(fp_poly
			(pts
				(xy -2.7686 -0.175768) (xy -2.7686 -1.124204) (xy -1.81991 -0.649986)
			)
			(stroke
				(width 0)
				(type default)
			)
			(fill yes)
			(layer "F.SilkS")
		)
		(fp_line
			(start -0.700024 1.074928)
			(end -0.700024 -1.074928)
			(stroke
				(width 0.1)
				(type default)
			)
			(layer "F.Fab")
		)
		(fp_line
			(start 0.700024 1.074928)
			(end -0.700024 1.074928)
			(stroke
				(width 0.1)
				(type default)
			)
			(layer "F.Fab")
		)
		(fp_line
			(start -0.700024 -1.074928)
			(end 0.700024 -1.074928)
			(stroke
				(width 0.1)
				(type default)
			)
			(layer "F.Fab")
		)
		(fp_line
			(start 0.700024 -1.074928)
			(end 0.700024 1.074928)
			(stroke
				(width 0.1)
				(type default)
			)
			(layer "F.Fab")
		)
		(fp_poly
			(pts
				(xy -2.7686 -1.124204) (xy -1.81991 -0.649986) (xy -2.7686 -0.175768)
			)
			(stroke
				(width 0)
				(type default)
			)
			(fill yes)
			(layer "F.Fab")
		)
		(pad "1" smd rect
			(at -1.100074 -0.649986)
			(size 0.4064 0.9144)
			(layers "F.Cu" "F.Mask" "F.Paste")
			(net "PWRGD_P12V_MEM_CPU0_R")
		)
		(pad "2" smd rect
			(at -1.100074 0)
			(size 0.4064 0.9144)
			(layers "F.Cu" "F.Mask" "F.Paste")
			(net "GND")
		)
		(pad "3" smd rect
			(at -1.100074 0.649986)
			(size 0.4064 0.9144)
			(layers "F.Cu" "F.Mask" "F.Paste")
			(net "PWRGD_P12V_MEM_CPU1_R")
		)
		(pad "4" smd rect
			(at 1.100074 0.649986)
			(size 0.4064 0.9144)
			(layers "F.Cu" "F.Mask" "F.Paste")
			(net "PWRGD_P12V_MEM")
		)
		(pad "5" smd rect
			(at 1.100074 0)
			(size 0.4064 0.9144)
			(layers "F.Cu" "F.Mask" "F.Paste")
			(net "P1V8_AUX")
		)
		(pad "6" smd rect
			(at 1.100074 -0.649986)
			(size 0.4064 0.9144)
			(layers "F.Cu" "F.Mask" "F.Paste")
			(net "PU_U38_6")
		)
	)
	(footprint ""
		(layer "F.Cu")
		(at 170.8912 -94.833948 -90)
		(property "Reference" "R6025"
			(at 0 0 270)
			(layer "F.SilkS")
			(hide yes)
			(effects
				(font
					(size 1.27 1.27)
				)
			)
		)
		(property "Value" ""
			(at 0 0 270)
			(layer "F.Fab")
			(effects
				(font
					(size 1.27 1.27)
				)
			)
		)
		(duplicate_pad_numbers_are_jumpers no)
		(fp_line
			(start -0.7874 0.4064)
			(end -0.7874 -0.4064)
			(stroke
				(width 0.1524)
				(type default)
			)
			(layer "F.SilkS")
		)
		(fp_line
			(start 0.7874 0.4064)
			(end -0.7874 0.4064)
			(stroke
				(width 0.1524)
				(type default)
			)
			(layer "F.SilkS")
		)
		(fp_line
			(start -0.7874 -0.4064)
			(end 0.7874 -0.4064)
			(stroke
				(width 0.1524)
				(type default)
			)
			(layer "F.SilkS")
		)
		(fp_line
			(start 0.7874 -0.4064)
			(end 0.7874 0.4064)
			(stroke
				(width 0.1524)
				(type default)
			)
			(layer "F.SilkS")
		)
		(fp_line
			(start -0.67945 0.3048)
			(end -0.67945 -0.305054)
			(stroke
				(width 0.1)
				(type default)
			)
			(layer "F.Fab")
		)
		(fp_line
			(start -0.12065 0.3048)
			(end -0.67945 0.3048)
			(stroke
				(width 0.1)
				(type default)
			)
			(layer "F.Fab")
		)
		(fp_line
			(start 0.120396 0.3048)
			(end 0.120396 0.2794)
			(stroke
				(width 0.1)
				(type default)
			)
			(layer "F.Fab")
		)
		(fp_line
			(start 0.67945 0.3048)
			(end 0.120396 0.3048)
			(stroke
				(width 0.1)
				(type default)
			)
			(layer "F.Fab")
		)
		(fp_line
			(start -0.12065 0.2794)
			(end -0.12065 0.3048)
			(stroke
				(width 0.1)
				(type default)
			)
			(layer "F.Fab")
		)
		(fp_line
			(start 0.120396 0.2794)
			(end -0.12065 0.2794)
			(stroke
				(width 0.1)
				(type default)
			)
			(layer "F.Fab")
		)
		(fp_line
			(start -0.12065 -0.2794)
			(end 0.12065 -0.2794)
			(stroke
				(width 0.1)
				(type default)
			)
			(layer "F.Fab")
		)
		(fp_line
			(start 0.12065 -0.2794)
			(end 0.12065 -0.3048)
			(stroke
				(width 0.1)
				(type default)
			)
			(layer "F.Fab")
		)
		(fp_line
			(start 0.12065 -0.3048)
			(end 0.67945 -0.3048)
			(stroke
				(width 0.1)
				(type default)
			)
			(layer "F.Fab")
		)
		(fp_line
			(start 0.67945 -0.3048)
			(end 0.67945 0.3048)
			(stroke
				(width 0.1)
				(type default)
			)
			(layer "F.Fab")
		)
		(fp_line
			(start -0.67945 -0.305054)
			(end -0.12065 -0.305054)
			(stroke
				(width 0.1)
				(type default)
			)
			(layer "F.Fab")
		)
		(fp_line
			(start -0.12065 -0.305054)
			(end -0.12065 -0.2794)
			(stroke
				(width 0.1)
				(type default)
			)
			(layer "F.Fab")
		)
		(pad "1" smd circle
			(at -0.40005 0 270)
			(size 0 0)
			(layers "F.Cu" "F.Mask" "F.Paste")
			(net "SGPIO_SCM_RESET_N")
		)
		(pad "2" smd circle
			(at 0.40005 0 270)
			(size 0 0)
			(layers "F.Cu" "F.Mask" "F.Paste")
			(net "SGPIO_SCM_RESET_R_N")
		)
	)
	(footprint ""
		(layer "F.Cu")
		(at 102.268782 -379.471428)
		(property "Reference" "C711"
			(at 0 0 0)
			(layer "F.SilkS")
			(hide yes)
			(effects
				(font
					(size 1.27 1.27)
				)
			)
		)
		(property "Value" ""
			(at 0 0 0)
			(layer "F.Fab")
			(effects
				(font
					(size 1.27 1.27)
				)
			)
		)
		(duplicate_pad_numbers_are_jumpers no)
		(fp_line
			(start -0.299974 -0.150114)
			(end 0.299974 -0.150114)
			(stroke
				(width 0.1)
				(type default)
			)
			(layer "F.Fab")
		)
		(fp_line
			(start -0.299974 0.150114)
			(end -0.299974 -0.150114)
			(stroke
				(width 0.1)
				(type default)
			)
			(layer "F.Fab")
		)
		(fp_line
			(start 0.299974 -0.150114)
			(end 0.299974 0.150114)
			(stroke
				(width 0.1)
				(type default)
			)
			(layer "F.Fab")
		)
		(fp_line
			(start 0.299974 0.150114)
			(end -0.299974 0.150114)
			(stroke
				(width 0.1)
				(type default)
			)
			(layer "F.Fab")
		)
		(pad "1" smd rect
			(at -0.2667 0)
			(size 0.3048 0.381)
			(layers "F.Cu" "F.Mask" "F.Paste")
			(net "P5E_CPU1_P1_TX_C_DP<15>")
		)
		(pad "2" smd rect
			(at 0.2667 0)
			(size 0.3048 0.381)
			(layers "F.Cu" "F.Mask" "F.Paste")
			(net "P5E_CPU1_P1_TX_DP<15>")
		)
	)
	(footprint ""
		(layer "F.Cu")
		(at 197.269608 -112.609376 180)
		(property "Reference" "R282"
			(at 0 0 180)
			(layer "F.SilkS")
			(hide yes)
			(effects
				(font
					(size 1.27 1.27)
				)
			)
		)
		(property "Value" ""
			(at 0 0 180)
			(layer "F.Fab")
			(effects
				(font
					(size 1.27 1.27)
				)
			)
		)
		(duplicate_pad_numbers_are_jumpers no)
		(fp_line
			(start 0.7874 0.4064)
			(end -0.7874 0.4064)
			(stroke
				(width 0.1524)
				(type default)
			)
			(layer "F.SilkS")
		)
		(fp_line
			(start 0.7874 -0.4064)
			(end 0.7874 0.4064)
			(stroke
				(width 0.1524)
				(type default)
			)
			(layer "F.SilkS")
		)
		(fp_line
			(start -0.7874 0.4064)
			(end -0.7874 -0.4064)
			(stroke
				(width 0.1524)
				(type default)
			)
			(layer "F.SilkS")
		)
		(fp_line
			(start -0.7874 -0.4064)
			(end 0.7874 -0.4064)
			(stroke
				(width 0.1524)
				(type default)
			)
			(layer "F.SilkS")
		)
		(fp_line
			(start 0.67945 0.3048)
			(end 0.120396 0.3048)
			(stroke
				(width 0.1)
				(type default)
			)
			(layer "F.Fab")
		)
		(fp_line
			(start 0.67945 -0.3048)
			(end 0.67945 0.3048)
			(stroke
				(width 0.1)
				(type default)
			)
			(layer "F.Fab")
		)
		(fp_line
			(start 0.12065 -0.2794)
			(end 0.12065 -0.3048)
			(stroke
				(width 0.1)
				(type default)
			)
			(layer "F.Fab")
		)
		(fp_line
			(start 0.12065 -0.3048)
			(end 0.67945 -0.3048)
			(stroke
				(width 0.1)
				(type default)
			)
			(layer "F.Fab")
		)
		(fp_line
			(start 0.120396 0.3048)
			(end 0.120396 0.2794)
			(stroke
				(width 0.1)
				(type default)
			)
			(layer "F.Fab")
		)
		(fp_line
			(start 0.120396 0.2794)
			(end -0.12065 0.2794)
			(stroke
				(width 0.1)
				(type default)
			)
			(layer "F.Fab")
		)
		(fp_line
			(start -0.12065 0.3048)
			(end -0.67945 0.3048)
			(stroke
				(width 0.1)
				(type default)
			)
			(layer "F.Fab")
		)
		(fp_line
			(start -0.12065 0.2794)
			(end -0.12065 0.3048)
			(stroke
				(width 0.1)
				(type default)
			)
			(layer "F.Fab")
		)
		(fp_line
			(start -0.12065 -0.2794)
			(end 0.12065 -0.2794)
			(stroke
				(width 0.1)
				(type default)
			)
			(layer "F.Fab")
		)
		(fp_line
			(start -0.12065 -0.305054)
			(end -0.12065 -0.2794)
			(stroke
				(width 0.1)
				(type default)
			)
			(layer "F.Fab")
		)
		(fp_line
			(start -0.67945 0.3048)
			(end -0.67945 -0.305054)
			(stroke
				(width 0.1)
				(type default)
			)
			(layer "F.Fab")
		)
		(fp_line
			(start -0.67945 -0.305054)
			(end -0.12065 -0.305054)
			(stroke
				(width 0.1)
				(type default)
			)
			(layer "F.Fab")
		)
		(pad "1" smd circle
			(at -0.40005 0 180)
			(size 0 0)
			(layers "F.Cu" "F.Mask" "F.Paste")
			(net "PVDDIO_P1_EN")
		)
		(pad "2" smd circle
			(at 0.40005 0 180)
			(size 0 0)
			(layers "F.Cu" "F.Mask" "F.Paste")
			(net "FM_PVDDIO_P1_EN")
		)
	)
)
